(kicad_pcb
	(version 20241229)
	(generator "pcbnew")
	(generator_version "9.0")
	(general
		(thickness 1.63)
		(legacy_teardrops no)
	)
	(paper "A4")
	(title_block
		(title "CM4 Baseboard")
		(date "2026-01-05")
		(rev "1.1.1")
		(company "Antmicro Ltd")
		(comment 1 "www.antmicro.com")
		(comment 9 "footprints 1-5 of 506")
	)
	(layers
		(0 "F.Cu" signal)
		(4 "In1.Cu" power)
		(6 "In2.Cu" power)
		(8 "In3.Cu" signal)
		(10 "In4.Cu" signal)
		(2 "B.Cu" signal)
		(9 "F.Adhes" user "F.Adhesive")
		(11 "B.Adhes" user "B.Adhesive")
		(13 "F.Paste" user)
		(15 "B.Paste" user)
		(5 "F.SilkS" user "F.Silkscreen")
		(7 "B.SilkS" user "B.Silkscreen")
		(1 "F.Mask" user)
		(3 "B.Mask" user)
		(17 "Dwgs.User" user "User.Drawings")
		(19 "Cmts.User" user "User.Comments")
		(21 "Eco1.User" user "User.Eco1")
		(23 "Eco2.User" user "User.Eco2")
		(25 "Edge.Cuts" user)
		(27 "Margin" user)
		(31 "F.CrtYd" user "F.Courtyard")
		(29 "B.CrtYd" user "B.Courtyard")
		(35 "F.Fab" user)
		(33 "B.Fab" user)
	)
	(footprint "antmicro-footprints:R_0402_1005Metric"
		(layer "F.Cu")
		(at 140.137962 132.6765 180)
		(descr "Resistor SMD 0402")
		(tags "resistor SMD 0402")
		(property "Reference" "R239"
			(at 0.87 -0.54 0)
			(layer "F.SilkS")
			(effects
				(font
					(size 0.7 0.7)
					(thickness 0.15)
				)
				(justify right bottom)
			)
		)
		(property "Value" "R_0R_0402"
			(at -1.011843 1.772047 0)
			(layer "F.Fab")
			(effects
				(font
					(size 0.7 0.7)
					(thickness 0.15)
				)
				(justify right bottom)
			)
		)
		(property "Datasheet" "https://industrial.panasonic.com/cdbs/www-data/pdf/RDA0000/AOA0000C301.pdf"
			(at 0 0 180)
			(layer "F.Fab")
			(hide yes)
			(effects
				(font
					(size 1.27 1.27)
					(thickness 0.15)
				)
			)
		)
		(property "Manufacturer" "Panasonic"
			(at 0 0 180)
			(unlocked yes)
			(layer "F.Fab")
			(hide yes)
			(effects
				(font
					(size 1 1)
					(thickness 0.15)
				)
			)
		)
		(property "MPN" "ERJ2GE0R00X"
			(at 0 0 180)
			(unlocked yes)
			(layer "F.Fab")
			(hide yes)
			(effects
				(font
					(size 1 1)
					(thickness 0.15)
				)
			)
		)
		(property "Val" "0R"
			(at 0 0 180)
			(unlocked yes)
			(layer "F.Fab")
			(hide yes)
			(effects
				(font
					(size 1 1)
					(thickness 0.15)
				)
			)
		)
		(property "License" "Apache-2.0"
			(at 0 0 180)
			(unlocked yes)
			(layer "F.Fab")
			(hide yes)
			(effects
				(font
					(size 1 1)
					(thickness 0.15)
				)
			)
		)
		(property "Author" "Antmicro"
			(at 0 0 180)
			(unlocked yes)
			(layer "F.Fab")
			(hide yes)
			(effects
				(font
					(size 1 1)
					(thickness 0.15)
				)
			)
		)
		(property "Tolerance" "~"
			(at 0 0 180)
			(unlocked yes)
			(layer "F.Fab")
			(hide yes)
			(effects
				(font
					(size 1 1)
					(thickness 0.15)
				)
			)
		)
		(property "Current" "1A"
			(at 0 0 180)
			(unlocked yes)
			(layer "F.Fab")
			(hide yes)
			(effects
				(font
					(size 1 1)
					(thickness 0.15)
				)
			)
		)
		(sheetname "/Compute module/")
		(sheetfile "compute-module.kicad_sch")
		(attr smd)
		(fp_rect
			(start -0.925 -0.47)
			(end 0.925 0.47)
			(stroke
				(width 0.05)
				(type default)
			)
			(fill no)
			(layer "F.CrtYd")
		)
		(fp_rect
			(start -0.5 -0.25)
			(end 0.5 0.25)
			(stroke
				(width 0.15)
				(type solid)
			)
			(fill no)
			(layer "F.Fab")
		)
		(fp_text user "License: Apache-2.0"
			(at -0.95 5.169 180)
			(layer "F.Fab")
			(effects
				(font
					(size 0.7 0.7)
					(thickness 0.15)
				)
				(justify left bottom)
			)
		)
		(fp_text user "Author: Antmicro"
			(at -0.95 4.169 180)
			(layer "F.Fab")
			(effects
				(font
					(size 0.7 0.7)
					(thickness 0.15)
				)
				(justify left bottom)
			)
		)
		(fp_text user "${REFERENCE}"
			(at -0.95 3.168 180)
			(layer "F.Fab")
			(effects
				(font
					(size 0.7 0.7)
					(thickness 0.15)
				)
				(justify left bottom)
			)
		)
		(pad "1" smd roundrect
			(at -0.48 0 180)
			(size 0.59 0.64)
			(layers "F.Cu" "F.Mask" "F.Paste")
			(roundrect_rratio 0.25)
			(net 447 "/Compute module/GPIO.0{slash}SDA0")
			(pintype "passive")
		)
		(pad "2" smd roundrect
			(at 0.48 0 180)
			(size 0.59 0.64)
			(layers "F.Cu" "F.Mask" "F.Paste")
			(roundrect_rratio 0.25)
			(net 141 "/CSI/I_{2}C_CSI0.SDA")
			(pintype "passive")
		)
	)
	(footprint "antmicro-footprints:TP_SMD_0.75mm"
		(layer "F.Cu")
		(at 59.967962 170.9165)
		(property "Reference" "TP403"
			(at -3.85 0.45 0)
			(layer "F.SilkS")
			(effects
				(font
					(size 0.7 0.7)
					(thickness 0.15)
				)
				(justify left bottom)
			)
		)
		(property "Value" "TP_0.75mm_SMD"
			(at 0 1.2 0)
			(layer "F.Fab")
			(effects
				(font
					(size 0.7 0.7)
					(thickness 0.15)
				)
				(justify left bottom)
			)
		)
		(property "MPN" ""
			(at 0 0 0)
			(unlocked yes)
			(layer "F.Fab")
			(hide yes)
			(effects
				(font
					(size 1 1)
					(thickness 0.15)
				)
			)
		)
		(property "Manufacturer" ""
			(at 0 0 0)
			(unlocked yes)
			(layer "F.Fab")
			(hide yes)
			(effects
				(font
					(size 1 1)
					(thickness 0.15)
				)
			)
		)
		(property "Author" "Antmicro"
			(at 0 0 0)
			(unlocked yes)
			(layer "F.Fab")
			(hide yes)
			(effects
				(font
					(size 1 1)
					(thickness 0.15)
				)
			)
		)
		(property "License" "Apache-2.0"
			(at 0 0 0)
			(unlocked yes)
			(layer "F.Fab")
			(hide yes)
			(effects
				(font
					(size 1 1)
					(thickness 0.15)
				)
			)
		)
		(sheetname "/Ethernet/")
		(sheetfile "ethernet.kicad_sch")
		(attr exclude_from_pos_files exclude_from_bom)
		(fp_circle
			(center 0 0)
			(end 0.475 0)
			(stroke
				(width 0.05)
				(type default)
			)
			(fill no)
			(layer "F.CrtYd")
		)
		(fp_text user "Author: Antmicro"
			(at -0.4 3.901 0)
			(layer "F.Fab")
			(effects
				(font
					(size 0.7 0.7)
					(thickness 0.15)
				)
				(justify left bottom)
			)
		)
		(fp_text user "License: Apache-2.0"
			(at -0.4 5.101 0)
			(layer "F.Fab")
			(effects
				(font
					(size 0.7 0.7)
					(thickness 0.15)
				)
				(justify left bottom)
			)
		)
		(fp_text user "${REFERENCE}"
			(at -0.4 2.7 0)
			(layer "F.Fab")
			(effects
				(font
					(size 0.7 0.7)
					(thickness 0.15)
				)
				(justify left bottom)
			)
		)
		(pad "1" smd circle
			(at 0 0)
			(size 0.75 0.75)
			(layers "F.Cu" "F.Mask")
			(net 47 "/Ethernet/POE_12V")
			(pinfunction "1")
			(pintype "passive")
		)
	)
	(footprint "antmicro-footprints:R_0402_1005Metric"
		(layer "F.Cu")
		(at 73.4 162.05)
		(descr "Resistor SMD 0402")
		(tags "resistor SMD 0402")
		(property "Reference" "R327"
			(at -8.76 -1.08 0)
			(layer "F.SilkS")
			(effects
				(font
					(size 0.7 0.7)
					(thickness 0.15)
				)
				(justify left bottom)
			)
		)
		(property "Value" "R_470R_0402"
			(at -1.011843 1.772047 0)
			(layer "F.Fab")
			(effects
				(font
					(size 0.7 0.7)
					(thickness 0.15)
				)
				(justify left bottom)
			)
		)
		(property "Datasheet" "https://www.bourns.com/docs/product-datasheets/cr.pdf"
			(at 0 0 0)
			(layer "F.Fab")
			(hide yes)
			(effects
				(font
					(size 1.27 1.27)
					(thickness 0.15)
				)
			)
		)
		(property "Manufacturer" "Bourns"
			(at 0 0 0)
			(unlocked yes)
			(layer "F.Fab")
			(hide yes)
			(effects
				(font
					(size 1 1)
					(thickness 0.15)
				)
			)
		)
		(property "MPN" "CR0402-FX-4700GLF"
			(at 0 0 0)
			(unlocked yes)
			(layer "F.Fab")
			(hide yes)
			(effects
				(font
					(size 1 1)
					(thickness 0.15)
				)
			)
		)
		(property "Val" "470R"
			(at 0 0 0)
			(unlocked yes)
			(layer "F.Fab")
			(hide yes)
			(effects
				(font
					(size 1 1)
					(thickness 0.15)
				)
			)
		)
		(property "License" "Apache-2.0"
			(at 0 0 0)
			(unlocked yes)
			(layer "F.Fab")
			(hide yes)
			(effects
				(font
					(size 1 1)
					(thickness 0.15)
				)
			)
		)
		(property "Author" "Antmicro"
			(at 0 0 0)
			(unlocked yes)
			(layer "F.Fab")
			(hide yes)
			(effects
				(font
					(size 1 1)
					(thickness 0.15)
				)
			)
		)
		(property "Tolerance" "1%"
			(at 0 0 0)
			(unlocked yes)
			(layer "F.Fab")
			(hide yes)
			(effects
				(font
					(size 1 1)
					(thickness 0.15)
				)
			)
		)
		(sheetname "/Supply/")
		(sheetfile "supply.kicad_sch")
		(attr smd)
		(fp_rect
			(start -0.925 -0.47)
			(end 0.925 0.47)
			(stroke
				(width 0.05)
				(type default)
			)
			(fill no)
			(layer "F.CrtYd")
		)
		(fp_rect
			(start -0.5 -0.25)
			(end 0.5 0.25)
			(stroke
				(width 0.15)
				(type solid)
			)
			(fill no)
			(layer "F.Fab")
		)
		(fp_text user "License: Apache-2.0"
			(at -0.95 5.169 0)
			(layer "F.Fab")
			(effects
				(font
					(size 0.7 0.7)
					(thickness 0.15)
				)
				(justify left bottom)
			)
		)
		(fp_text user "${REFERENCE}"
			(at -0.95 3.168 0)
			(layer "F.Fab")
			(effects
				(font
					(size 0.7 0.7)
					(thickness 0.15)
				)
				(justify left bottom)
			)
		)
		(fp_text user "Author: Antmicro"
			(at -0.95 4.169 0)
			(layer "F.Fab")
			(effects
				(font
					(size 0.7 0.7)
					(thickness 0.15)
				)
				(justify left bottom)
			)
		)
		(pad "1" smd roundrect
			(at -0.48 0)
			(size 0.59 0.64)
			(layers "F.Cu" "F.Mask" "F.Paste")
			(roundrect_rratio 0.25)
			(net 476 "Net-(D306-A)")
			(pintype "passive")
		)
		(pad "2" smd roundrect
			(at 0.48 0)
			(size 0.59 0.64)
			(layers "F.Cu" "F.Mask" "F.Paste")
			(roundrect_rratio 0.25)
			(net 9 "+3V3")
			(pintype "passive")
		)
	)
	(footprint "antmicro-footprints:TP_SMD_0.75mm"
		(layer "F.Cu")
		(at 76.692962 167.2165 180)
		(property "Reference" "TP208"
			(at 8.865 0.96 0)
			(layer "F.SilkS")
			(effects
				(font
					(size 0.7 0.7)
					(thickness 0.15)
				)
				(justify right bottom)
			)
		)
		(property "Value" "TP_0.75mm_SMD"
			(at 0 1.2 0)
			(layer "F.Fab")
			(effects
				(font
					(size 0.7 0.7)
					(thickness 0.15)
				)
				(justify right bottom)
			)
		)
		(property "Author" "Antmicro"
			(at 0 0 180)
			(unlocked yes)
			(layer "F.Fab")
			(hide yes)
			(effects
				(font
					(size 1 1)
					(thickness 0.15)
				)
			)
		)
		(property "License" "Apache-2.0"
			(at 0 0 180)
			(unlocked yes)
			(layer "F.Fab")
			(hide yes)
			(effects
				(font
					(size 1 1)
					(thickness 0.15)
				)
			)
		)
		(property "MPN" ""
			(at 0 0 180)
			(unlocked yes)
			(layer "F.Fab")
			(hide yes)
			(effects
				(font
					(size 1 1)
					(thickness 0.15)
				)
			)
		)
		(property "Manufacturer" ""
			(at 0 0 180)
			(unlocked yes)
			(layer "F.Fab")
			(hide yes)
			(effects
				(font
					(size 1 1)
					(thickness 0.15)
				)
			)
		)
		(sheetname "/Compute module/")
		(sheetfile "compute-module.kicad_sch")
		(attr exclude_from_pos_files exclude_from_bom)
		(fp_circle
			(center 0 0)
			(end 0.475 0)
			(stroke
				(width 0.05)
				(type default)
			)
			(fill no)
			(layer "F.CrtYd")
		)
		(fp_text user "License: Apache-2.0"
			(at -0.4 5.101 180)
			(layer "F.Fab")
			(effects
				(font
					(size 0.7 0.7)
					(thickness 0.15)
				)
				(justify left bottom)
			)
		)
		(fp_text user "Author: Antmicro"
			(at -0.4 3.901 180)
			(layer "F.Fab")
			(effects
				(font
					(size 0.7 0.7)
					(thickness 0.15)
				)
				(justify left bottom)
			)
		)
		(fp_text user "${REFERENCE}"
			(at -0.4 2.7 180)
			(layer "F.Fab")
			(effects
				(font
					(size 0.7 0.7)
					(thickness 0.15)
				)
				(justify left bottom)
			)
		)
		(pad "1" smd circle
			(at 0 0 180)
			(size 0.75 0.75)
			(layers "F.Cu" "F.Mask")
			(net 255 "/Compute module/~{RPi_RST}")
			(pinfunction "1")
			(pintype "passive")
		)
	)
	(footprint "antmicro-footprints:SOT-23-3"
		(layer "F.Cu")
		(at 83.967962 157.1165 -90)
		(property "Reference" "Q212"
			(at 2.74 -1.36 180)
			(layer "F.SilkS")
			(effects
				(font
					(size 0.7 0.7)
					(thickness 0.15)
				)
				(justify right bottom)
			)
		)
		(property "Value" "SSM3J332R"
			(at -1.9 2.7 90)
			(layer "F.Fab")
			(effects
				(font
					(size 0.7 0.7)
					(thickness 0.15)
				)
				(justify right bottom)
			)
		)
		(property "Datasheet" "https://www.mouser.com/datasheet/2/408/SSM3J332R_datasheet_en_20181015-1150575.pdf"
			(at 0 0 270)
			(layer "F.Fab")
			(hide yes)
			(effects
				(font
					(size 1.27 1.27)
					(thickness 0.15)
				)
			)
		)
		(property "MPN" "SSM3J332R,LF"
			(at 0 0 270)
			(unlocked yes)
			(layer "F.Fab")
			(hide yes)
			(effects
				(font
					(size 1 1)
					(thickness 0.15)
				)
			)
		)
		(property "Manufacturer" "Toshiba"
			(at 0 0 270)
			(unlocked yes)
			(layer "F.Fab")
			(hide yes)
			(effects
				(font
					(size 1 1)
					(thickness 0.15)
				)
			)
		)
		(property "Author" "Antmicro"
			(at 0 0 270)
			(unlocked yes)
			(layer "F.Fab")
			(hide yes)
			(effects
				(font
					(size 1 1)
					(thickness 0.15)
				)
			)
		)
		(property "License" "Apache-2.0"
			(at 0 0 270)
			(unlocked yes)
			(layer "F.Fab")
			(hide yes)
			(effects
				(font
					(size 1 1)
					(thickness 0.15)
				)
			)
		)
		(sheetname "/Compute module/")
		(sheetfile "compute-module.kicad_sch")
		(attr smd)
		(fp_line
			(start -0.7 1.5)
			(end -0.7 1.35)
			(stroke
				(width 0.15)
				(type solid)
			)
			(layer "F.SilkS")
		)
		(fp_line
			(start 0.7 1.5)
			(end -0.7 1.5)
			(stroke
				(width 0.15)
				(type solid)
			)
			(layer "F.SilkS")
		)
		(fp_line
			(start 0.7 0.4)
			(end 0.7 1.5)
			(stroke
				(width 0.15)
				(type solid)
			)
			(layer "F.SilkS")
		)
		(fp_line
			(start 0.7 -0.4)
			(end 0.7 -1.5)
			(stroke
				(width 0.15)
				(type solid)
			)
			(layer "F.SilkS")
		)
		(fp_line
			(start -1.45 -1.35)
			(end -0.85 -1.35)
			(stroke
				(width 0.15)
				(type solid)
			)
			(layer "F.SilkS")
		)
		(fp_line
			(start -0.85 -1.35)
			(end -0.7 -1.5)
			(stroke
				(width 0.15)
				(type solid)
			)
			(layer "F.SilkS")
		)
		(fp_line
			(start 0.7 -1.5)
			(end -0.7 -1.5)
			(stroke
				(width 0.15)
				(type solid)
			)
			(layer "F.SilkS")
		)
		(fp_line
			(start -0.85 1.65)
			(end -0.85 1.4)
			(stroke
				(width 0.05)
				(type solid)
			)
			(layer "F.CrtYd")
		)
		(fp_line
			(start 0.85 1.65)
			(end -0.85 1.65)
			(stroke
				(width 0.05)
				(type solid)
			)
			(layer "F.CrtYd")
		)
		(fp_line
			(start -1.75 1.4)
			(end -1.75 0.5)
			(stroke
				(width 0.05)
				(type solid)
			)
			(layer "F.CrtYd")
		)
		(fp_line
			(start -0.85 1.4)
			(end -1.75 1.4)
			(stroke
				(width 0.05)
				(type solid)
			)
			(layer "F.CrtYd")
		)
		(fp_line
			(start -1.75 0.5)
			(end -0.85 0.5)
			(stroke
				(width 0.05)
				(type solid)
			)
			(layer "F.CrtYd")
		)
		(fp_line
			(start -0.85 0.5)
			(end -0.85 -0.5)
			(stroke
				(width 0.05)
				(type solid)
			)
			(layer "F.CrtYd")
		)
		(fp_line
			(start 0.85 0.45)
			(end 0.85 1.65)
			(stroke
				(width 0.05)
				(type solid)
			)
			(layer "F.CrtYd")
		)
		(fp_line
			(start 1.75 0.45)
			(end 0.85 0.45)
			(stroke
				(width 0.05)
				(type solid)
			)
			(layer "F.CrtYd")
		)
		(fp_line
			(start 0.825 -0.45)
			(end 1.75 -0.45)
			(stroke
				(width 0.05)
				(type solid)
			)
			(layer "F.CrtYd")
		)
		(fp_line
			(start 1.75 -0.45)
			(end 1.75 0.45)
			(stroke
				(width 0.05)
				(type solid)
			)
			(layer "F.CrtYd")
		)
		(fp_line
			(start -1.75 -0.5)
			(end -1.75 -1.4)
			(stroke
				(width 0.05)
				(type solid)
			)
			(layer "F.CrtYd")
		)
		(fp_line
			(start -0.85 -0.5)
			(end -1.75 -0.5)
			(stroke
				(width 0.05)
				(type solid)
			)
			(layer "F.CrtYd")
		)
		(fp_line
			(start -0.9 -1.4)
			(end -1.75 -1.4)
			(stroke
				(width 0.05)
				(type solid)
			)
			(layer "F.CrtYd")
		)
		(fp_line
			(start -0.9 -1.6)
			(end -0.9 -1.4)
			(stroke
				(width 0.05)
				(type solid)
			)
			(layer "F.CrtYd")
		)
		(fp_line
			(start -0.9 -1.6)
			(end 0.825 -1.6)
			(stroke
				(width 0.05)
				(type solid)
			)
			(layer "F.CrtYd")
		)
		(fp_line
			(start 0.825 -1.6)
			(end 0.825 -0.45)
			(stroke
				(width 0.05)
				(type solid)
			)
			(layer "F.CrtYd")
		)
		(fp_line
			(start -0.712 1.519)
			(end 0.688 1.519)
			(stroke
				(width 0.15)
				(type solid)
			)
			(layer "F.Fab")
		)
		(fp_line
			(start 0.688 1.519)
			(end 0.688 -1.52)
			(stroke
				(width 0.15)
				(type solid)
			)
			(layer "F.Fab")
		)
		(fp_line
			(start -0.712 -1.325)
			(end -0.712 1.523)
			(stroke
				(width 0.15)
				(type solid)
			)
			(layer "F.Fab")
		)
		(fp_line
			(start -0.437 -1.526)
			(end -0.712 -1.325)
			(stroke
				(width 0.15)
				(type solid)
			)
			(layer "F.Fab")
		)
		(fp_line
			(start -0.437 -1.526)
			(end 0.688 -1.526)
			(stroke
				(width 0.15)
				(type solid)
			)
			(layer "F.Fab")
		)
		(fp_text user "${REFERENCE}"
			(at -1.837 4 270)
			(layer "F.Fab")
			(effects
				(font
					(size 0.7 0.7)
					(thickness 0.15)
				)
				(justify left bottom)
			)
		)
		(fp_text user "License: Apache-2.0"
			(at -1.8 6.8 270)
			(layer "F.Fab")
			(effects
				(font
					(size 0.7 0.7)
					(thickness 0.15)
				)
				(justify left bottom)
			)
		)
		(fp_text user "Author: Antmicro"
			(at -1.837 5.3 270)
			(layer "F.Fab")
			(effects
				(font
					(size 0.7 0.7)
					(thickness 0.15)
				)
				(justify left bottom)
			)
		)
		(pad "1" smd roundrect
			(at -1.1 -0.951 270)
			(size 1 0.6)
			(layers "F.Cu" "F.Mask" "F.Paste")
			(roundrect_rratio 0.15)
			(net 444 "Net-(Q211-D)")
			(pinfunction "G")
			(pintype "input")
		)
		(pad "2" smd roundrect
			(at -1.1 0.949 270)
			(size 1 0.6)
			(layers "F.Cu" "F.Mask" "F.Paste")
			(roundrect_rratio 0.15)
			(net 24 "/Compute module/USBA_VBUS")
			(pinfunction "S")
			(pintype "passive")
		)
		(pad "3" smd roundrect
			(at 1.1 -0.0005 270)
			(size 1 0.6)
			(layers "F.Cu" "F.Mask" "F.Paste")
			(roundrect_rratio 0.15)
			(net 238 "/Compute module/GPIO.17")
			(pinfunction "D")
			(pintype "passive")
		)
	)
)
